# T6G (Grand Teton) — schematic netlist excerpt (pin names and nets, part order shuffled) for the footprints in the layout excerpt that follows; sources: Cadence DE-HDL packaged netlist, KiCad conversion of 04192023_DAF0TMB3IC0_F0TG_MB_C_brd_V02_OCP.brd

R2230  Q_RES  10K 1% EMPTY  pkg 0402LF  page 268 : A = P3V3_AUX ; B = A_P12V_STBY_FPH_GATE
C1523  Q_CAP  0.1UF 16V 10% X7R  pkg C0402  page 174 : A = PVDD18_S5_P0 ; B = GND

(kicad_pcb
	(version 20260206)
	(generator "pcbnew")
	(generator_version "10.0")
	(general
		(thickness 1.6)
		(legacy_teardrops no)
	)
	(paper "A4")
	(title_block
		(title "04192023_DAF0TMB3IC0_F0TG_MB_C_brd_V02_OCP.brd")
		(comment 1 "Grand Teton / footprints 4907-4908 of 8354")
	)
	(layers
		(0 "F.Cu" signal "TOP")
		(4 "In1.Cu" signal "GND")
		(6 "In2.Cu" signal "IN1")
		(8 "In3.Cu" signal "GND1")
		(10 "In4.Cu" signal "IN2")
		(12 "In5.Cu" signal "GND2")
		(14 "In6.Cu" signal "IN3")
		(16 "In7.Cu" signal "GND3")
		(18 "In8.Cu" signal "VCC")
		(20 "In9.Cu" signal "VCC1")
		(22 "In10.Cu" signal "GND4")
		(24 "In11.Cu" signal "IN4")
		(26 "In12.Cu" signal "GND5")
		(28 "In13.Cu" signal "IN5")
		(30 "In14.Cu" signal "GND6")
		(32 "In15.Cu" signal "IN6")
		(34 "In16.Cu" signal "GND7")
		(2 "B.Cu" signal "BOTTOM")
		(9 "F.Adhes" user "F.Adhesive")
		(11 "B.Adhes" user "B.Adhesive")
		(13 "F.Paste" user "Package Geometry/Pastemask Top")
		(15 "B.Paste" user "Package Geometry/Pastemask Bottom")
		(5 "F.SilkS" user "Ref Des/Silkscreen Top")
		(7 "B.SilkS" user "Ref Des/Silkscreen Bottom")
		(1 "F.Mask" user "Board Geometry/Soldermask Top")
		(3 "B.Mask" user "Board Geometry/Soldermask Bottom")
		(17 "Dwgs.User" user "User.Drawings")
		(19 "Cmts.User" user "User.Comments")
		(21 "Eco1.User" user "User.Eco1")
		(23 "Eco2.User" user "User.Eco2")
		(25 "Edge.Cuts" user "Board Geometry/Outline")
		(27 "Margin" user)
		(31 "F.CrtYd" user "Package Geometry/Place Bound Top")
		(29 "B.CrtYd" user "Package Geometry/Place Bound Bottom")
		(35 "F.Fab" user "Ref Des/Assembly Top")
		(33 "B.Fab" user "Ref Des/Assembly Bottom")
	)
	(footprint ""
		(layer "F.Cu")
		(at 150.400258 -116.449094)
		(property "Reference" "R2230"
			(at 0 0 0)
			(layer "F.SilkS")
			(hide yes)
			(effects
				(font
					(size 1.27 1.27)
				)
			)
		)
		(property "Value" ""
			(at 0 0 0)
			(layer "F.Fab")
			(effects
				(font
					(size 1.27 1.27)
				)
			)
		)
		(duplicate_pad_numbers_are_jumpers no)
		(fp_line
			(start -0.7874 -0.4064)
			(end 0.7874 -0.4064)
			(stroke
				(width 0.1524)
				(type default)
			)
			(layer "F.SilkS")
		)
		(fp_line
			(start -0.7874 0.4064)
			(end -0.7874 -0.4064)
			(stroke
				(width 0.1524)
				(type default)
			)
			(layer "F.SilkS")
		)
		(fp_line
			(start 0.7874 -0.4064)
			(end 0.7874 0.4064)
			(stroke
				(width 0.1524)
				(type default)
			)
			(layer "F.SilkS")
		)
		(fp_line
			(start 0.7874 0.4064)
			(end -0.7874 0.4064)
			(stroke
				(width 0.1524)
				(type default)
			)
			(layer "F.SilkS")
		)
		(fp_line
			(start -0.67945 -0.305054)
			(end -0.12065 -0.305054)
			(stroke
				(width 0.1)
				(type default)
			)
			(layer "F.Fab")
		)
		(fp_line
			(start -0.67945 0.3048)
			(end -0.67945 -0.305054)
			(stroke
				(width 0.1)
				(type default)
			)
			(layer "F.Fab")
		)
		(fp_line
			(start -0.12065 -0.305054)
			(end -0.12065 -0.2794)
			(stroke
				(width 0.1)
				(type default)
			)
			(layer "F.Fab")
		)
		(fp_line
			(start -0.12065 -0.2794)
			(end 0.12065 -0.2794)
			(stroke
				(width 0.1)
				(type default)
			)
			(layer "F.Fab")
		)
		(fp_line
			(start -0.12065 0.2794)
			(end -0.12065 0.3048)
			(stroke
				(width 0.1)
				(type default)
			)
			(layer "F.Fab")
		)
		(fp_line
			(start -0.12065 0.3048)
			(end -0.67945 0.3048)
			(stroke
				(width 0.1)
				(type default)
			)
			(layer "F.Fab")
		)
		(fp_line
			(start 0.120396 0.2794)
			(end -0.12065 0.2794)
			(stroke
				(width 0.1)
				(type default)
			)
			(layer "F.Fab")
		)
		(fp_line
			(start 0.120396 0.3048)
			(end 0.120396 0.2794)
			(stroke
				(width 0.1)
				(type default)
			)
			(layer "F.Fab")
		)
		(fp_line
			(start 0.12065 -0.3048)
			(end 0.67945 -0.3048)
			(stroke
				(width 0.1)
				(type default)
			)
			(layer "F.Fab")
		)
		(fp_line
			(start 0.12065 -0.2794)
			(end 0.12065 -0.3048)
			(stroke
				(width 0.1)
				(type default)
			)
			(layer "F.Fab")
		)
		(fp_line
			(start 0.67945 -0.3048)
			(end 0.67945 0.3048)
			(stroke
				(width 0.1)
				(type default)
			)
			(layer "F.Fab")
		)
		(fp_line
			(start 0.67945 0.3048)
			(end 0.120396 0.3048)
			(stroke
				(width 0.1)
				(type default)
			)
			(layer "F.Fab")
		)
		(pad "1" smd circle
			(at -0.40005 0)
			(size 0 0)
			(layers "F.Cu" "F.Mask" "F.Paste")
			(net "P3V3_AUX")
		)
		(pad "2" smd circle
			(at 0.40005 0)
			(size 0 0)
			(layers "F.Cu" "F.Mask" "F.Paste")
			(net "A_P12V_STBY_FPH_GATE")
		)
	)
	(footprint ""
		(layer "F.Cu")
		(at 230.675688 -158.981648 180)
		(property "Reference" "C1523"
			(at 0 0 180)
			(layer "F.SilkS")
			(hide yes)
			(effects
				(font
					(size 1.27 1.27)
				)
			)
		)
		(property "Value" ""
			(at 0 0 180)
			(layer "F.Fab")
			(effects
				(font
					(size 1.27 1.27)
				)
			)
		)
		(duplicate_pad_numbers_are_jumpers no)
		(fp_line
			(start 0.7874 0.4064)
			(end -0.7874 0.4064)
			(stroke
				(width 0.1524)
				(type default)
			)
			(layer "F.SilkS")
		)
		(fp_line
			(start 0.7874 -0.4064)
			(end 0.7874 0.4064)
			(stroke
				(width 0.1524)
				(type default)
			)
			(layer "F.SilkS")
		)
		(fp_line
			(start -0.7874 0.4064)
			(end -0.7874 -0.4064)
			(stroke
				(width 0.1524)
				(type default)
			)
			(layer "F.SilkS")
		)
		(fp_line
			(start -0.7874 -0.4064)
			(end 0.7874 -0.4064)
			(stroke
				(width 0.1524)
				(type default)
			)
			(layer "F.SilkS")
		)
		(fp_line
			(start 0.67945 0.3048)
			(end 0.120396 0.3048)
			(stroke
				(width 0.1)
				(type default)
			)
			(layer "F.Fab")
		)
		(fp_line
			(start 0.67945 -0.3048)
			(end 0.67945 0.3048)
			(stroke
				(width 0.1)
				(type default)
			)
			(layer "F.Fab")
		)
		(fp_line
			(start 0.12065 -0.2794)
			(end 0.12065 -0.3048)
			(stroke
				(width 0.1)
				(type default)
			)
			(layer "F.Fab")
		)
		(fp_line
			(start 0.12065 -0.3048)
			(end 0.67945 -0.3048)
			(stroke
				(width 0.1)
				(type default)
			)
			(layer "F.Fab")
		)
		(fp_line
			(start 0.120396 0.3048)
			(end 0.120396 0.2794)
			(stroke
				(width 0.1)
				(type default)
			)
			(layer "F.Fab")
		)
		(fp_line
			(start 0.120396 0.2794)
			(end -0.12065 0.2794)
			(stroke
				(width 0.1)
				(type default)
			)
			(layer "F.Fab")
		)
		(fp_line
			(start -0.12065 0.3048)
			(end -0.67945 0.3048)
			(stroke
				(width 0.1)
				(type default)
			)
			(layer "F.Fab")
		)
		(fp_line
			(start -0.12065 0.2794)
			(end -0.12065 0.3048)
			(stroke
				(width 0.1)
				(type default)
			)
			(layer "F.Fab")
		)
		(fp_line
			(start -0.12065 -0.2794)
			(end 0.12065 -0.2794)
			(stroke
				(width 0.1)
				(type default)
			)
			(layer "F.Fab")
		)
		(fp_line
			(start -0.12065 -0.305054)
			(end -0.12065 -0.2794)
			(stroke
				(width 0.1)
				(type default)
			)
			(layer "F.Fab")
		)
		(fp_line
			(start -0.67945 0.3048)
			(end -0.67945 -0.305054)
			(stroke
				(width 0.1)
				(type default)
			)
			(layer "F.Fab")
		)
		(fp_line
			(start -0.67945 -0.305054)
			(end -0.12065 -0.305054)
			(stroke
				(width 0.1)
				(type default)
			)
			(layer "F.Fab")
		)
		(pad "1" smd circle
			(at -0.40005 0 180)
			(size 0 0)
			(layers "F.Cu" "F.Mask" "F.Paste")
			(net "PVDD18_S5_P0")
		)
		(pad "2" smd circle
			(at 0.40005 0 180)
			(size 0 0)
			(layers "F.Cu" "F.Mask" "F.Paste")
			(net "GND")
		)
	)
)
